(kicad_pcb
	(version 20241229)
	(generator "pcbnew")
	(generator_version "9.0")
	(general
		(thickness 1.711)
		(legacy_teardrops no)
	)
	(paper "A4")
	(title_block
		(title "Antmicro Baseboard for Jetson AGX Thor")
		(date "2026-02-18")
		(rev "1.1.0")
		(company "Antmicro Ltd")
		(comment 1 "www.antmicro.com")
		(comment 9 "footprints 256-259 of 1170")
	)
	(layers
		(0 "F.Cu" signal)
		(4 "In1.Cu" signal)
		(6 "In2.Cu" signal)
		(8 "In3.Cu" signal)
		(10 "In4.Cu" jumper)
		(12 "In5.Cu" signal)
		(14 "In6.Cu" signal)
		(16 "In7.Cu" signal)
		(18 "In8.Cu" signal)
		(2 "B.Cu" signal)
		(9 "F.Adhes" user "F.Adhesive")
		(11 "B.Adhes" user "B.Adhesive")
		(13 "F.Paste" user)
		(15 "B.Paste" user)
		(5 "F.SilkS" user "F.Silkscreen")
		(7 "B.SilkS" user "B.Silkscreen")
		(1 "F.Mask" user)
		(3 "B.Mask" user)
		(17 "Dwgs.User" user "User.Drawings")
		(19 "Cmts.User" user "User.Comments")
		(21 "Eco1.User" user "User.Eco1")
		(23 "Eco2.User" user "User.Eco2")
		(25 "Edge.Cuts" user)
		(27 "Margin" user)
		(31 "F.CrtYd" user "F.Courtyard")
		(29 "B.CrtYd" user "B.Courtyard")
		(35 "F.Fab" user)
		(33 "B.Fab" user)
	)
	(footprint "antmicro-footprints:C_0402_1005Metric"
		(layer "F.Cu")
		(at 94 61.5 180)
		(descr "Capacitor SMD 0402")
		(tags "capacitor SMD 0402")
		(property "Reference" "C8"
			(at -8.4 -0.75 0)
			(layer "F.SilkS")
			(effects
				(font
					(size 0.7 0.7)
					(thickness 0.15)
				)
				(justify right top)
			)
		)
		(property "Value" "C_100n_0402"
			(at -1.022927 2.155213 0)
			(layer "F.Fab")
			(effects
				(font
					(size 0.7 0.7)
					(thickness 0.15)
				)
				(justify right top)
			)
		)
		(property "Datasheet" "https://www.murata.com/products/productdetail?partno=GRM155R61H104KE14%23"
			(at 0 0 0)
			(layer "F.Fab")
			(hide yes)
			(effects
				(font
					(size 1.27 1.27)
					(thickness 0.15)
				)
			)
		)
		(property "Description" "SMD Multilayer Ceramic Capacitor, 0.1 µF, 50 V, 0402 [1005 Metric], ± 10%, X5R, GRM Series"
			(at 0 0 0)
			(layer "F.Fab")
			(hide yes)
			(effects
				(font
					(size 1.27 1.27)
					(thickness 0.15)
				)
			)
		)
		(property "MPN" "GRM155R61H104KE14D"
			(at 0 0 180)
			(unlocked yes)
			(layer "F.Fab")
			(hide yes)
			(effects
				(font
					(size 1 1)
					(thickness 0.15)
				)
			)
		)
		(property "Manufacturer" "Murata"
			(at 0 0 180)
			(unlocked yes)
			(layer "F.Fab")
			(hide yes)
			(effects
				(font
					(size 1 1)
					(thickness 0.15)
				)
			)
		)
		(property "License" "Apache-2.0"
			(at 0 0 180)
			(unlocked yes)
			(layer "F.Fab")
			(hide yes)
			(effects
				(font
					(size 1 1)
					(thickness 0.15)
				)
			)
		)
		(property "Author" "Antmicro"
			(at 0 0 180)
			(unlocked yes)
			(layer "F.Fab")
			(hide yes)
			(effects
				(font
					(size 1 1)
					(thickness 0.15)
				)
			)
		)
		(property "Val" "100n"
			(at 0 0 180)
			(unlocked yes)
			(layer "F.Fab")
			(hide yes)
			(effects
				(font
					(size 1 1)
					(thickness 0.15)
				)
			)
		)
		(property "Voltage" "50V"
			(at 0 0 180)
			(unlocked yes)
			(layer "F.Fab")
			(hide yes)
			(effects
				(font
					(size 1 1)
					(thickness 0.15)
				)
			)
		)
		(property "Dielectric" "X5R"
			(at 0 0 180)
			(unlocked yes)
			(layer "F.Fab")
			(hide yes)
			(effects
				(font
					(size 1 1)
					(thickness 0.15)
				)
			)
		)
		(property "Public" "False"
			(at 0 0 180)
			(unlocked yes)
			(layer "F.Fab")
			(hide yes)
			(effects
				(font
					(size 1 1)
					(thickness 0.15)
				)
			)
		)
		(sheetname "/SoM_Power/")
		(sheetfile "som_power.kicad_sch")
		(attr smd exclude_from_pos_files exclude_from_bom dnp)
		(fp_poly
			(pts
				(xy -0.925 -0.47) (xy 0.925 -0.47) (xy 0.925 0.47) (xy -0.925 0.47)
			)
			(stroke
				(width 0.05)
				(type default)
			)
			(fill no)
			(layer "F.CrtYd")
		)
		(fp_line
			(start 0.504 0.248)
			(end -0.494 0.248)
			(stroke
				(width 0.15)
				(type solid)
			)
			(layer "F.Fab")
		)
		(fp_line
			(start 0.504 -0.25)
			(end 0.504 0.248)
			(stroke
				(width 0.15)
				(type solid)
			)
			(layer "F.Fab")
		)
		(fp_line
			(start -0.494 0.248)
			(end -0.494 -0.25)
			(stroke
				(width 0.15)
				(type solid)
			)
			(layer "F.Fab")
		)
		(fp_line
			(start -0.494 -0.25)
			(end 0.504 -0.25)
			(stroke
				(width 0.15)
				(type solid)
			)
			(layer "F.Fab")
		)
		(fp_text user "${REFERENCE}"
			(at -0.939 4.599 0)
			(layer "F.Fab")
			(effects
				(font
					(size 0.7 0.7)
					(thickness 0.15)
				)
				(justify right top)
			)
		)
		(fp_text user "Author: Antmicro"
			(at -0.939 3.399 0)
			(layer "F.Fab")
			(effects
				(font
					(size 0.7 0.7)
					(thickness 0.15)
				)
				(justify right top)
			)
		)
		(fp_text user "License: Apache-2.0"
			(at -0.939 5.799 0)
			(layer "F.Fab")
			(effects
				(font
					(size 0.7 0.7)
					(thickness 0.15)
				)
				(justify right top)
			)
		)
		(pad "1" smd roundrect
			(at -0.48 0 180)
			(size 0.59 0.64)
			(layers "F.Cu" "F.Mask" "F.Paste")
			(roundrect_rratio 0.25)
			(net 1 "GND")
			(pintype "passive")
		)
		(pad "2" smd roundrect
			(at 0.48 0 180)
			(size 0.59 0.64)
			(layers "F.Cu" "F.Mask" "F.Paste")
			(roundrect_rratio 0.25)
			(net 1287 "/SoM_Power/MODULE_POWER_ON")
			(pintype "passive")
		)
	)
	(footprint "antmicro-footprints:USON-10_2.5x1mm_P0.5mm"
		(layer "F.Cu")
		(at 220.815 111.427 180)
		(descr "USON-10 2.5x1mm_ Pitch 0.5mm")
		(tags "USON-10 2.5x1mm Pitch 0.5mm")
		(property "Reference" "U27"
			(at -1.045 -2.103 90)
			(layer "F.SilkS")
			(effects
				(font
					(size 0.7 0.7)
					(thickness 0.15)
				)
				(justify right top)
			)
		)
		(property "Value" "TPD4E05U06QDQARQ1"
			(at 0.018 2.499 0)
			(layer "F.Fab")
			(effects
				(font
					(size 0.7 0.7)
					(thickness 0.15)
				)
				(justify right top)
			)
		)
		(property "Datasheet" "https://www.ti.com/lit/ds/symlink/tpd4e05u06-q1.pdf?HQS=dis-mous-null-mousermode-dsf-pf-null-wwe&ts=1663591265741&ref_url=https%253A%252F%252Fwww.mouser.com%252F"
			(at 0 0 0)
			(layer "F.Fab")
			(hide yes)
			(effects
				(font
					(size 1.27 1.27)
					(thickness 0.15)
				)
			)
		)
		(property "Description" "TVS diode array, 12 kV, USON-10, 5.5 V, 0.5 pF"
			(at 0 0 0)
			(layer "F.Fab")
			(hide yes)
			(effects
				(font
					(size 1.27 1.27)
					(thickness 0.15)
				)
			)
		)
		(property "Manufacturer" "Texas Instruments"
			(at 0 0 180)
			(unlocked yes)
			(layer "F.Fab")
			(hide yes)
			(effects
				(font
					(size 1 1)
					(thickness 0.15)
				)
			)
		)
		(property "MPN" "TPD4E05U06QDQARQ1"
			(at 0 0 180)
			(unlocked yes)
			(layer "F.Fab")
			(hide yes)
			(effects
				(font
					(size 1 1)
					(thickness 0.15)
				)
			)
		)
		(property "Author" "Antmicro"
			(at 0 0 180)
			(unlocked yes)
			(layer "F.Fab")
			(hide yes)
			(effects
				(font
					(size 1 1)
					(thickness 0.15)
				)
			)
		)
		(property "License" "Apache-2.0"
			(at 0 0 180)
			(unlocked yes)
			(layer "F.Fab")
			(hide yes)
			(effects
				(font
					(size 1 1)
					(thickness 0.15)
				)
			)
		)
		(sheetname "/USB Hub/")
		(sheetfile "usb_hub.kicad_sch")
		(attr smd)
		(fp_line
			(start 0.498 1.398)
			(end -0.5 1.398)
			(stroke
				(width 0.15)
				(type solid)
			)
			(layer "F.SilkS")
		)
		(fp_line
			(start 0.498 -1.401)
			(end -0.5 -1.401)
			(stroke
				(width 0.15)
				(type solid)
			)
			(layer "F.SilkS")
		)
		(fp_circle
			(center -0.68 -1.27)
			(end -0.63 -1.27)
			(stroke
				(width 0.15)
				(type solid)
			)
			(fill yes)
			(layer "F.SilkS")
		)
		(fp_rect
			(start -0.8 -1.5)
			(end 0.8 1.499)
			(stroke
				(width 0.05)
				(type solid)
			)
			(fill no)
			(layer "F.CrtYd")
		)
		(fp_line
			(start 0.498 -1.25)
			(end 0.498 1.249)
			(stroke
				(width 0.15)
				(type solid)
			)
			(layer "F.Fab")
		)
		(fp_line
			(start 0.498 -1.25)
			(end -0.25 -1.25)
			(stroke
				(width 0.15)
				(type solid)
			)
			(layer "F.Fab")
		)
		(fp_line
			(start -0.25 -1.25)
			(end -0.5 -1)
			(stroke
				(width 0.15)
				(type solid)
			)
			(layer "F.Fab")
		)
		(fp_line
			(start -0.5 1.249)
			(end 0.498 1.249)
			(stroke
				(width 0.15)
				(type solid)
			)
			(layer "F.Fab")
		)
		(fp_line
			(start -0.5 -1)
			(end -0.5 1.249)
			(stroke
				(width 0.15)
				(type solid)
			)
			(layer "F.Fab")
		)
		(fp_text user "Author: Antmicro"
			(at -0.802 5.7 0)
			(layer "F.Fab")
			(effects
				(font
					(size 0.7 0.7)
					(thickness 0.15)
				)
				(justify right top)
			)
		)
		(fp_text user "License: Apache-2.0"
			(at -0.802 6.9 0)
			(layer "F.Fab")
			(effects
				(font
					(size 0.7 0.7)
					(thickness 0.15)
				)
				(justify right top)
			)
		)
		(fp_text user "${REFERENCE}"
			(at -0.802 4.498 0)
			(layer "F.Fab")
			(effects
				(font
					(size 0.7 0.7)
					(thickness 0.15)
				)
				(justify right top)
			)
		)
		(pad "1" smd roundrect
			(at -0.387 -1 90)
			(size 0.25 0.55)
			(layers "F.Cu" "F.Mask" "F.Paste")
			(roundrect_rratio 0.25)
			(net 103 "/USB Hub/USBC3_CONN_TX2_N")
			(pintype "passive")
		)
		(pad "2" smd roundrect
			(at -0.387 -0.5 90)
			(size 0.25 0.55)
			(layers "F.Cu" "F.Mask" "F.Paste")
			(roundrect_rratio 0.25)
			(net 174 "/USB Hub/USBC3_CONN_TX2_P")
			(pintype "passive")
		)
		(pad "3" smd roundrect
			(at -0.387 0 90)
			(size 0.4 0.55)
			(layers "F.Cu" "F.Mask" "F.Paste")
			(roundrect_rratio 0.25)
			(net 1 "GND")
			(pintype "power_in")
		)
		(pad "4" smd roundrect
			(at -0.387 0.498 90)
			(size 0.25 0.55)
			(layers "F.Cu" "F.Mask" "F.Paste")
			(roundrect_rratio 0.25)
			(net 512 "/USB Hub/USBC3_RX_{2}+")
			(pintype "passive")
		)
		(pad "5" smd roundrect
			(at -0.387 0.998 90)
			(size 0.25 0.55)
			(layers "F.Cu" "F.Mask" "F.Paste")
			(roundrect_rratio 0.25)
			(net 511 "/USB Hub/USBC3_RX_{2}-")
			(pintype "passive")
		)
		(pad "6" smd roundrect
			(at 0.385 0.998 90)
			(size 0.25 0.55)
			(layers "F.Cu" "F.Mask" "F.Paste")
			(roundrect_rratio 0.25)
			(net 511 "/USB Hub/USBC3_RX_{2}-")
			(pintype "passive")
		)
		(pad "7" smd roundrect
			(at 0.385 0.498 90)
			(size 0.25 0.55)
			(layers "F.Cu" "F.Mask" "F.Paste")
			(roundrect_rratio 0.25)
			(net 512 "/USB Hub/USBC3_RX_{2}+")
			(pintype "passive")
		)
		(pad "8" smd roundrect
			(at 0.385 0 90)
			(size 0.4 0.55)
			(layers "F.Cu" "F.Mask" "F.Paste")
			(roundrect_rratio 0.25)
			(net 1 "GND")
			(pintype "passive")
		)
		(pad "9" smd roundrect
			(at 0.385 -0.5 90)
			(size 0.25 0.55)
			(layers "F.Cu" "F.Mask" "F.Paste")
			(roundrect_rratio 0.25)
			(net 174 "/USB Hub/USBC3_CONN_TX2_P")
			(pintype "passive")
		)
		(pad "10" smd roundrect
			(at 0.385 -1 90)
			(size 0.25 0.55)
			(layers "F.Cu" "F.Mask" "F.Paste")
			(roundrect_rratio 0.25)
			(net 103 "/USB Hub/USBC3_CONN_TX2_N")
			(pintype "passive")
		)
	)
	(footprint "antmicro-footprints:C_0402_1005Metric"
		(layer "F.Cu")
		(at 168.924468 134.56 180)
		(descr "Capacitor SMD 0402")
		(tags "capacitor SMD 0402")
		(property "Reference" "C217"
			(at 1.024468 0.16 0)
			(layer "F.SilkS")
			(effects
				(font
					(size 0.7 0.7)
					(thickness 0.15)
				)
				(justify right top)
			)
		)
		(property "Value" "C_100n_0402"
			(at -1.022927 2.155213 0)
			(layer "F.Fab")
			(effects
				(font
					(size 0.7 0.7)
					(thickness 0.15)
				)
				(justify right top)
			)
		)
		(property "Datasheet" "https://www.murata.com/products/productdetail?partno=GRM155R61H104KE14%23"
			(at 0 0 0)
			(layer "F.Fab")
			(hide yes)
			(effects
				(font
					(size 1.27 1.27)
					(thickness 0.15)
				)
			)
		)
		(property "Description" "SMD Multilayer Ceramic Capacitor, 0.1 µF, 50 V, 0402 [1005 Metric], ± 10%, X5R, GRM Series"
			(at 0 0 0)
			(layer "F.Fab")
			(hide yes)
			(effects
				(font
					(size 1.27 1.27)
					(thickness 0.15)
				)
			)
		)
		(property "MPN" "GRM155R61H104KE14D"
			(at 0 0 180)
			(unlocked yes)
			(layer "F.Fab")
			(hide yes)
			(effects
				(font
					(size 1 1)
					(thickness 0.15)
				)
			)
		)
		(property "Manufacturer" "Murata"
			(at 0 0 180)
			(unlocked yes)
			(layer "F.Fab")
			(hide yes)
			(effects
				(font
					(size 1 1)
					(thickness 0.15)
				)
			)
		)
		(property "License" "Apache-2.0"
			(at 0 0 180)
			(unlocked yes)
			(layer "F.Fab")
			(hide yes)
			(effects
				(font
					(size 1 1)
					(thickness 0.15)
				)
			)
		)
		(property "Author" "Antmicro"
			(at 0 0 180)
			(unlocked yes)
			(layer "F.Fab")
			(hide yes)
			(effects
				(font
					(size 1 1)
					(thickness 0.15)
				)
			)
		)
		(property "Val" "100n"
			(at 0 0 180)
			(unlocked yes)
			(layer "F.Fab")
			(hide yes)
			(effects
				(font
					(size 1 1)
					(thickness 0.15)
				)
			)
		)
		(property "Voltage" "50V"
			(at 0 0 180)
			(unlocked yes)
			(layer "F.Fab")
			(hide yes)
			(effects
				(font
					(size 1 1)
					(thickness 0.15)
				)
			)
		)
		(property "Dielectric" "X5R"
			(at 0 0 180)
			(unlocked yes)
			(layer "F.Fab")
			(hide yes)
			(effects
				(font
					(size 1 1)
					(thickness 0.15)
				)
			)
		)
		(property "Public" "False"
			(at 0 0 180)
			(unlocked yes)
			(layer "F.Fab")
			(hide yes)
			(effects
				(font
					(size 1 1)
					(thickness 0.15)
				)
			)
		)
		(sheetname "/DCDC/")
		(sheetfile "dcdc.kicad_sch")
		(attr smd)
		(fp_rect
			(start -0.925 -0.47)
			(end 0.925 0.47)
			(stroke
				(width 0.05)
				(type default)
			)
			(fill no)
			(layer "F.CrtYd")
		)
		(fp_line
			(start 0.504 0.248)
			(end -0.494 0.248)
			(stroke
				(width 0.15)
				(type solid)
			)
			(layer "F.Fab")
		)
		(fp_line
			(start 0.504 -0.25)
			(end 0.504 0.248)
			(stroke
				(width 0.15)
				(type solid)
			)
			(layer "F.Fab")
		)
		(fp_line
			(start -0.494 0.248)
			(end -0.494 -0.25)
			(stroke
				(width 0.15)
				(type solid)
			)
			(layer "F.Fab")
		)
		(fp_line
			(start -0.494 -0.25)
			(end 0.504 -0.25)
			(stroke
				(width 0.15)
				(type solid)
			)
			(layer "F.Fab")
		)
		(fp_text user "License: Apache-2.0"
			(at -0.939 5.799 0)
			(layer "F.Fab")
			(effects
				(font
					(size 0.7 0.7)
					(thickness 0.15)
				)
				(justify right top)
			)
		)
		(fp_text user "${REFERENCE}"
			(at -0.939 4.599 0)
			(layer "F.Fab")
			(effects
				(font
					(size 0.7 0.7)
					(thickness 0.15)
				)
				(justify right top)
			)
		)
		(fp_text user "Author: Antmicro"
			(at -0.939 3.399 0)
			(layer "F.Fab")
			(effects
				(font
					(size 0.7 0.7)
					(thickness 0.15)
				)
				(justify right top)
			)
		)
		(pad "1" smd roundrect
			(at -0.48 0 180)
			(size 0.59 0.64)
			(layers "F.Cu" "F.Mask" "F.Paste")
			(roundrect_rratio 0.25)
			(net 1 "GND")
			(pintype "passive")
		)
		(pad "2" smd roundrect
			(at 0.48 0 180)
			(size 0.59 0.64)
			(layers "F.Cu" "F.Mask" "F.Paste")
			(roundrect_rratio 0.25)
			(net 4 "+3V3_AON")
			(pintype "passive")
		)
	)
	(footprint "antmicro-footprints:R_0402_1005Metric"
		(layer "F.Cu")
		(at 214.8 107 90)
		(descr "Resistor SMD 0402")
		(tags "resistor SMD 0402")
		(property "Reference" "R276"
			(at -1.75 1.465 90)
			(layer "F.SilkS")
			(effects
				(font
					(size 0.7 0.7)
					(thickness 0.15)
				)
				(justify left bottom)
			)
		)
		(property "Value" "R_0R_0402"
			(at -1.011843 1.772046 90)
			(layer "F.Fab")
			(effects
				(font
					(size 0.7 0.7)
					(thickness 0.15)
				)
				(justify left bottom)
			)
		)
		(property "Datasheet" "https://industrial.panasonic.com/cdbs/www-data/pdf/RDA0000/AOA0000C301.pdf"
			(at 0 0 90)
			(layer "F.Fab")
			(hide yes)
			(effects
				(font
					(size 1.27 1.27)
					(thickness 0.15)
				)
			)
		)
		(property "Description" "SMD Chip Resistor, Jumper, 0 ohm, 100 mW, 0402 [1005 Metric], Thick Film, General Purpose"
			(at 0 0 90)
			(layer "F.Fab")
			(hide yes)
			(effects
				(font
					(size 1.27 1.27)
					(thickness 0.15)
				)
			)
		)
		(property "Manufacturer" "Panasonic"
			(at 0 0 90)
			(unlocked yes)
			(layer "F.Fab")
			(hide yes)
			(effects
				(font
					(size 1 1)
					(thickness 0.15)
				)
			)
		)
		(property "MPN" "ERJ2GE0R00X"
			(at 0 0 90)
			(unlocked yes)
			(layer "F.Fab")
			(hide yes)
			(effects
				(font
					(size 1 1)
					(thickness 0.15)
				)
			)
		)
		(property "Val" "0R"
			(at 0 0 90)
			(unlocked yes)
			(layer "F.Fab")
			(hide yes)
			(effects
				(font
					(size 1 1)
					(thickness 0.15)
				)
			)
		)
		(property "License" "Apache-2.0"
			(at 0 0 90)
			(unlocked yes)
			(layer "F.Fab")
			(hide yes)
			(effects
				(font
					(size 1 1)
					(thickness 0.15)
				)
			)
		)
		(property "Author" "Antmicro"
			(at 0 0 90)
			(unlocked yes)
			(layer "F.Fab")
			(hide yes)
			(effects
				(font
					(size 1 1)
					(thickness 0.15)
				)
			)
		)
		(property "Tolerance" "~"
			(at 0 0 90)
			(unlocked yes)
			(layer "F.Fab")
			(hide yes)
			(effects
				(font
					(size 1 1)
					(thickness 0.15)
				)
			)
		)
		(property "Current" "1A"
			(at 0 0 90)
			(unlocked yes)
			(layer "F.Fab")
			(hide yes)
			(effects
				(font
					(size 1 1)
					(thickness 0.15)
				)
			)
		)
		(sheetname "/Recovery USB/")
		(sheetfile "recovery_usb.kicad_sch")
		(attr smd)
		(fp_poly
			(pts
				(xy -0.925 -0.47) (xy -0.925 0.47) (xy 0.925 0.47) (xy 0.925 -0.47)
			)
			(stroke
				(width 0.05)
				(type default)
			)
			(fill no)
			(layer "F.CrtYd")
		)
		(fp_poly
			(pts
				(xy -0.5 -0.25) (xy -0.5 0.25) (xy 0.5 0.25) (xy 0.5 -0.25)
			)
			(stroke
				(width 0.15)
				(type solid)
			)
			(fill no)
			(layer "F.Fab")
		)
		(fp_text user "Author: Antmicro"
			(at -0.95 4.169 90)
			(layer "F.Fab")
			(effects
				(font
					(size 0.7 0.7)
					(thickness 0.15)
				)
				(justify left bottom)
			)
		)
		(fp_text user "License: Apache-2.0"
			(at -0.949999 5.169 90)
			(layer "F.Fab")
			(effects
				(font
					(size 0.7 0.7)
					(thickness 0.15)
				)
				(justify left bottom)
			)
		)
		(fp_text user "${REFERENCE}"
			(at -0.95 3.168 90)
			(layer "F.Fab")
			(effects
				(font
					(size 0.7 0.7)
					(thickness 0.15)
				)
				(justify left bottom)
			)
		)
		(pad "1" smd roundrect
			(at -0.48 0 90)
			(size 0.59 0.64)
			(layers "F.Cu" "F.Mask" "F.Paste")
			(roundrect_rratio 0.25)
			(net 1 "GND")
			(pintype "passive")
		)
		(pad "2" smd roundrect
			(at 0.48 0 90)
			(size 0.59 0.64)
			(layers "F.Cu" "F.Mask" "F.Paste")
			(roundrect_rratio 0.25)
			(net 1021 "/Recovery USB/~{USBC2_EN_MUX}")
			(pintype "passive")
		)
	)
)
